(kicad_pcb
	(version 20260206)
	(generator "pcbnew")
	(generator_version "10.0")
	(general
		(thickness 1.6)
		(legacy_teardrops no)
	)
	(paper "A4")
	(title_block
		(title "Wiwynn_Tioga_Pass_MB.brd")
		(comment 1 "Tioga Pass / footprints 4616-4622 of 4770")
	)
	(layers
		(0 "F.Cu" signal "TOP")
		(4 "In1.Cu" signal "L2GND")
		(6 "In2.Cu" signal "L3")
		(8 "In3.Cu" signal "L4GND")
		(10 "In4.Cu" signal "L5")
		(12 "In5.Cu" signal "L6GND")
		(14 "In6.Cu" signal "L7VCC")
		(16 "In7.Cu" signal "L8VCC")
		(18 "In8.Cu" signal "L9GND")
		(20 "In9.Cu" signal "L10")
		(22 "In10.Cu" signal "L11GND")
		(24 "In11.Cu" signal "L12")
		(26 "In12.Cu" signal "L13GND")
		(2 "B.Cu" signal "BOTTOM")
		(9 "F.Adhes" user "F.Adhesive")
		(11 "B.Adhes" user "B.Adhesive")
		(13 "F.Paste" user "Package Geometry/Pastemask Top")
		(15 "B.Paste" user "Package Geometry/Pastemask Bottom")
		(5 "F.SilkS" user "Ref Des/Silkscreen Top")
		(7 "B.SilkS" user "Ref Des/Silkscreen Bottom")
		(1 "F.Mask" user "Board Geometry/Soldermask Top")
		(3 "B.Mask" user "Board Geometry/Soldermask Bottom")
		(17 "Dwgs.User" user "User.Drawings")
		(19 "Cmts.User" user "User.Comments")
		(21 "Eco1.User" user "User.Eco1")
		(23 "Eco2.User" user "User.Eco2")
		(25 "Edge.Cuts" user "Board Geometry/Outline")
		(27 "Margin" user)
		(31 "F.CrtYd" user "Package Geometry/Place Bound Top")
		(29 "B.CrtYd" user "Package Geometry/Place Bound Bottom")
		(35 "F.Fab" user "Ref Des/Assembly Top")
		(33 "B.Fab" user "Ref Des/Assembly Bottom")
	)
	(footprint ""
		(layer "B.Cu")
		(at 420.776146 -48.922432 -90)
		(property "Reference" "R1T8"
			(at 0 0 90)
			(layer "B.SilkS")
			(hide yes)
			(effects
				(font
					(size 1.27 1.27)
				)
				(justify mirror)
			)
		)
		(property "Value" ""
			(at 0 0 90)
			(layer "B.Fab")
			(effects
				(font
					(size 1.27 1.27)
				)
				(justify mirror)
			)
		)
		(duplicate_pad_numbers_are_jumpers no)
		(fp_poly
			(pts
				(xy 0.2794 -0.1016) (xy -0.2794 -0.1016) (xy -0.2794 0.9906) (xy 0.2794 0.9906)
			)
			(stroke
				(width 0)
				(type default)
			)
			(fill no)
			(layer "B.CrtYd")
		)
		(fp_line
			(start -0.2794 0.9906)
			(end -0.2794 -0.1016)
			(stroke
				(width 0.1)
				(type default)
			)
			(layer "B.Fab")
		)
		(fp_line
			(start 0.2794 0.9906)
			(end -0.2794 0.9906)
			(stroke
				(width 0.1)
				(type default)
			)
			(layer "B.Fab")
		)
		(fp_line
			(start -0.2794 -0.1016)
			(end 0.2794 -0.1016)
			(stroke
				(width 0.1)
				(type default)
			)
			(layer "B.Fab")
		)
		(fp_line
			(start 0.2794 -0.1016)
			(end 0.2794 0.9906)
			(stroke
				(width 0.1)
				(type default)
			)
			(layer "B.Fab")
		)
		(pad "1" smd rect
			(at 0 0 90)
			(size 0.508 0.508)
			(layers "B.Cu" "B.Mask" "B.Paste")
			(net "SMB_SLOTX24_STBY_LVC3_SDA_R")
		)
		(pad "2" smd rect
			(at 0 0.889 90)
			(size 0.508 0.508)
			(layers "B.Cu" "B.Mask" "B.Paste")
			(net "SMB_SLOTX24_BMC_STBY_LVC3_SDA")
		)
		(zone
			(layer "B.Cu")
			(hatch none 0.5)
			(connect_pads
				(clearance 0)
			)
			(min_thickness 0.25)
			(keepout
				(tracks not_allowed)
				(vias allowed)
				(pads allowed)
				(copperpour not_allowed)
				(footprints allowed)
			)
			(placement
				(enabled no)
				(sheetname "")
			)
			(fill
				(thermal_gap 0.5)
				(thermal_bridge_width 0.5)
				(island_removal_mode 0)
			)
			(polygon
				(pts
					(xy 420.141146 -48.668432) (xy 420.141146 -49.176432) (xy 420.522146 -49.176432) (xy 420.522146 -48.668432)
				)
			)
		)
		(zone
			(layer "B.Cu")
			(hatch none 0.5)
			(connect_pads
				(clearance 0)
			)
			(min_thickness 0.25)
			(keepout
				(tracks allowed)
				(vias not_allowed)
				(pads allowed)
				(copperpour not_allowed)
				(footprints allowed)
			)
			(placement
				(enabled no)
				(sheetname "")
			)
			(fill
				(thermal_gap 0.5)
				(thermal_bridge_width 0.5)
				(island_removal_mode 0)
			)
			(polygon
				(pts
					(xy 420.522146 -48.668432) (xy 420.522146 -49.176432) (xy 420.141146 -49.176432) (xy 420.141146 -48.668432)
				)
			)
		)
	)
	(footprint ""
		(layer "B.Cu")
		(at 361.826556 -122.510042 -90)
		(property "Reference" "R778"
			(at 0.8382 -0.67818 270)
			(unlocked yes)
			(layer "B.SilkS")
			(effects
				(font
					(size 0.4064 0.254)
					(thickness 0.1524)
				)
				(justify left mirror)
			)
		)
		(property "Value" ""
			(at 0 0 90)
			(layer "B.Fab")
			(effects
				(font
					(size 1.27 1.27)
				)
				(justify mirror)
			)
		)
		(duplicate_pad_numbers_are_jumpers no)
		(fp_poly
			(pts
				(xy 0.2794 -0.1016) (xy -0.2794 -0.1016) (xy -0.2794 0.9906) (xy 0.2794 0.9906)
			)
			(stroke
				(width 0)
				(type default)
			)
			(fill no)
			(layer "B.CrtYd")
		)
		(fp_line
			(start -0.2794 0.9906)
			(end -0.2794 -0.1016)
			(stroke
				(width 0.1)
				(type default)
			)
			(layer "B.Fab")
		)
		(fp_line
			(start 0.2794 0.9906)
			(end -0.2794 0.9906)
			(stroke
				(width 0.1)
				(type default)
			)
			(layer "B.Fab")
		)
		(fp_line
			(start -0.2794 -0.1016)
			(end 0.2794 -0.1016)
			(stroke
				(width 0.1)
				(type default)
			)
			(layer "B.Fab")
		)
		(fp_line
			(start 0.2794 -0.1016)
			(end 0.2794 0.9906)
			(stroke
				(width 0.1)
				(type default)
			)
			(layer "B.Fab")
		)
		(pad "1" smd rect
			(at 0 0 90)
			(size 0.508 0.508)
			(layers "B.Cu" "B.Mask" "B.Paste")
			(net "P3E_CPU0_PE1_PCH_RXN<11>")
		)
		(pad "2" smd rect
			(at 0 0.889 90)
			(size 0.508 0.508)
			(layers "B.Cu" "B.Mask" "B.Paste")
			(net "P3E_CPU0_PE1_PCH_CON_RXN<11>")
		)
		(zone
			(layer "B.Cu")
			(hatch none 0.5)
			(connect_pads
				(clearance 0)
			)
			(min_thickness 0.25)
			(keepout
				(tracks not_allowed)
				(vias allowed)
				(pads allowed)
				(copperpour not_allowed)
				(footprints allowed)
			)
			(placement
				(enabled no)
				(sheetname "")
			)
			(fill
				(thermal_gap 0.5)
				(thermal_bridge_width 0.5)
				(island_removal_mode 0)
			)
			(polygon
				(pts
					(xy 361.191556 -122.256042) (xy 361.191556 -122.764042) (xy 361.572556 -122.764042) (xy 361.572556 -122.256042)
				)
			)
		)
		(zone
			(layer "B.Cu")
			(hatch none 0.5)
			(connect_pads
				(clearance 0)
			)
			(min_thickness 0.25)
			(keepout
				(tracks allowed)
				(vias not_allowed)
				(pads allowed)
				(copperpour not_allowed)
				(footprints allowed)
			)
			(placement
				(enabled no)
				(sheetname "")
			)
			(fill
				(thermal_gap 0.5)
				(thermal_bridge_width 0.5)
				(island_removal_mode 0)
			)
			(polygon
				(pts
					(xy 361.572556 -122.256042) (xy 361.572556 -122.764042) (xy 361.191556 -122.764042) (xy 361.191556 -122.256042)
				)
			)
		)
	)
	(footprint ""
		(layer "B.Cu")
		(at 373.498618 -89.78011)
		(property "Reference" "C7C19"
			(at 0 0 0)
			(layer "B.SilkS")
			(hide yes)
			(effects
				(font
					(size 1.27 1.27)
				)
				(justify mirror)
			)
		)
		(property "Value" ""
			(at 0 0 0)
			(layer "B.Fab")
			(effects
				(font
					(size 1.27 1.27)
				)
				(justify mirror)
			)
		)
		(duplicate_pad_numbers_are_jumpers no)
		(fp_poly
			(pts
				(xy -0.3048 -0.1016) (xy -0.3048 0.9906) (xy 0.3048 0.9906) (xy 0.3048 -0.1016)
			)
			(stroke
				(width 0)
				(type default)
			)
			(fill no)
			(layer "B.CrtYd")
		)
		(fp_line
			(start -0.3048 -0.1016)
			(end 0.3048 -0.1016)
			(stroke
				(width 0.1)
				(type default)
			)
			(layer "B.Fab")
		)
		(fp_line
			(start -0.3048 0.9906)
			(end -0.3048 -0.1016)
			(stroke
				(width 0.1)
				(type default)
			)
			(layer "B.Fab")
		)
		(fp_line
			(start 0.3048 -0.1016)
			(end 0.3048 0.9906)
			(stroke
				(width 0.1)
				(type default)
			)
			(layer "B.Fab")
		)
		(fp_line
			(start 0.3048 0.9906)
			(end -0.3048 0.9906)
			(stroke
				(width 0.1)
				(type default)
			)
			(layer "B.Fab")
		)
		(pad "1" smd rect
			(at 0 0 180)
			(size 0.508 0.508)
			(layers "B.Cu" "B.Mask" "B.Paste")
			(net "RST_RTCRST_N")
		)
		(pad "2" smd rect
			(at 0 0.889 180)
			(size 0.508 0.508)
			(layers "B.Cu" "B.Mask" "B.Paste")
			(net "GND")
		)
		(zone
			(layer "B.Cu")
			(hatch none 0.5)
			(connect_pads
				(clearance 0)
			)
			(min_thickness 0.25)
			(keepout
				(tracks allowed)
				(vias not_allowed)
				(pads allowed)
				(copperpour not_allowed)
				(footprints allowed)
			)
			(placement
				(enabled no)
				(sheetname "")
			)
			(fill
				(thermal_gap 0.5)
				(thermal_bridge_width 0.5)
				(island_removal_mode 0)
			)
			(polygon
				(pts
					(xy 373.752618 -89.52611) (xy 373.244618 -89.52611) (xy 373.244618 -89.14511) (xy 373.752618 -89.14511)
				)
			)
		)
		(zone
			(layer "B.Cu")
			(hatch none 0.5)
			(connect_pads
				(clearance 0)
			)
			(min_thickness 0.25)
			(keepout
				(tracks not_allowed)
				(vias allowed)
				(pads allowed)
				(copperpour not_allowed)
				(footprints allowed)
			)
			(placement
				(enabled no)
				(sheetname "")
			)
			(fill
				(thermal_gap 0.5)
				(thermal_bridge_width 0.5)
				(island_removal_mode 0)
			)
			(polygon
				(pts
					(xy 373.752618 -89.14511) (xy 373.244618 -89.14511) (xy 373.244618 -89.52611) (xy 373.752618 -89.52611)
				)
			)
		)
	)
	(footprint ""
		(layer "B.Cu")
		(at 117.221 -78.74 -90)
		(property "Reference" "R7P8"
			(at 0 0 90)
			(layer "B.SilkS")
			(hide yes)
			(effects
				(font
					(size 1.27 1.27)
				)
				(justify mirror)
			)
		)
		(property "Value" ""
			(at 0 0 90)
			(layer "B.Fab")
			(effects
				(font
					(size 1.27 1.27)
				)
				(justify mirror)
			)
		)
		(duplicate_pad_numbers_are_jumpers no)
		(fp_poly
			(pts
				(xy 0.2794 -0.1016) (xy -0.2794 -0.1016) (xy -0.2794 0.9906) (xy 0.2794 0.9906)
			)
			(stroke
				(width 0)
				(type default)
			)
			(fill no)
			(layer "B.CrtYd")
		)
		(fp_line
			(start -0.2794 0.9906)
			(end -0.2794 -0.1016)
			(stroke
				(width 0.1)
				(type default)
			)
			(layer "B.Fab")
		)
		(fp_line
			(start 0.2794 0.9906)
			(end -0.2794 0.9906)
			(stroke
				(width 0.1)
				(type default)
			)
			(layer "B.Fab")
		)
		(fp_line
			(start -0.2794 -0.1016)
			(end 0.2794 -0.1016)
			(stroke
				(width 0.1)
				(type default)
			)
			(layer "B.Fab")
		)
		(fp_line
			(start 0.2794 -0.1016)
			(end 0.2794 0.9906)
			(stroke
				(width 0.1)
				(type default)
			)
			(layer "B.Fab")
		)
		(pad "1" smd rect
			(at 0 0 90)
			(size 0.508 0.508)
			(layers "B.Cu" "B.Mask" "B.Paste")
			(net "A_CPU1_PE3_RBIAS")
		)
		(pad "2" smd rect
			(at 0 0.889 90)
			(size 0.508 0.508)
			(layers "B.Cu" "B.Mask" "B.Paste")
			(net "GND")
		)
		(zone
			(layer "B.Cu")
			(hatch none 0.5)
			(connect_pads
				(clearance 0)
			)
			(min_thickness 0.25)
			(keepout
				(tracks not_allowed)
				(vias allowed)
				(pads allowed)
				(copperpour not_allowed)
				(footprints allowed)
			)
			(placement
				(enabled no)
				(sheetname "")
			)
			(fill
				(thermal_gap 0.5)
				(thermal_bridge_width 0.5)
				(island_removal_mode 0)
			)
			(polygon
				(pts
					(xy 116.586 -78.486) (xy 116.586 -78.994) (xy 116.967 -78.994) (xy 116.967 -78.486)
				)
			)
		)
		(zone
			(layer "B.Cu")
			(hatch none 0.5)
			(connect_pads
				(clearance 0)
			)
			(min_thickness 0.25)
			(keepout
				(tracks allowed)
				(vias not_allowed)
				(pads allowed)
				(copperpour not_allowed)
				(footprints allowed)
			)
			(placement
				(enabled no)
				(sheetname "")
			)
			(fill
				(thermal_gap 0.5)
				(thermal_bridge_width 0.5)
				(island_removal_mode 0)
			)
			(polygon
				(pts
					(xy 116.967 -78.486) (xy 116.967 -78.994) (xy 116.586 -78.994) (xy 116.586 -78.486)
				)
			)
		)
	)
	(footprint ""
		(layer "B.Cu")
		(at 372.5164 -91.567 90)
		(property "Reference" "R3N13"
			(at 0 0 90)
			(layer "B.SilkS")
			(hide yes)
			(effects
				(font
					(size 1.27 1.27)
				)
				(justify mirror)
			)
		)
		(property "Value" ""
			(at 0 0 90)
			(layer "B.Fab")
			(effects
				(font
					(size 1.27 1.27)
				)
				(justify mirror)
			)
		)
		(duplicate_pad_numbers_are_jumpers no)
		(fp_poly
			(pts
				(xy 0.2794 -0.1016) (xy -0.2794 -0.1016) (xy -0.2794 0.9906) (xy 0.2794 0.9906)
			)
			(stroke
				(width 0)
				(type default)
			)
			(fill no)
			(layer "B.CrtYd")
		)
		(fp_line
			(start 0.2794 -0.1016)
			(end 0.2794 0.9906)
			(stroke
				(width 0.1)
				(type default)
			)
			(layer "B.Fab")
		)
		(fp_line
			(start -0.2794 -0.1016)
			(end 0.2794 -0.1016)
			(stroke
				(width 0.1)
				(type default)
			)
			(layer "B.Fab")
		)
		(fp_line
			(start 0.2794 0.9906)
			(end -0.2794 0.9906)
			(stroke
				(width 0.1)
				(type default)
			)
			(layer "B.Fab")
		)
		(fp_line
			(start -0.2794 0.9906)
			(end -0.2794 -0.1016)
			(stroke
				(width 0.1)
				(type default)
			)
			(layer "B.Fab")
		)
		(pad "1" smd rect
			(at 0 0 270)
			(size 0.508 0.508)
			(layers "B.Cu" "B.Mask" "B.Paste")
			(net "P3V3_STBY")
		)
		(pad "2" smd rect
			(at 0 0.889 270)
			(size 0.508 0.508)
			(layers "B.Cu" "B.Mask" "B.Paste")
			(net "IRQ_LVC3_WAKE_N")
		)
		(zone
			(layer "B.Cu")
			(hatch none 0.5)
			(connect_pads
				(clearance 0)
			)
			(min_thickness 0.25)
			(keepout
				(tracks allowed)
				(vias not_allowed)
				(pads allowed)
				(copperpour not_allowed)
				(footprints allowed)
			)
			(placement
				(enabled no)
				(sheetname "")
			)
			(fill
				(thermal_gap 0.5)
				(thermal_bridge_width 0.5)
				(island_removal_mode 0)
			)
			(polygon
				(pts
					(xy 372.7704 -91.821) (xy 372.7704 -91.313) (xy 373.1514 -91.313) (xy 373.1514 -91.821)
				)
			)
		)
		(zone
			(layer "B.Cu")
			(hatch none 0.5)
			(connect_pads
				(clearance 0)
			)
			(min_thickness 0.25)
			(keepout
				(tracks not_allowed)
				(vias allowed)
				(pads allowed)
				(copperpour not_allowed)
				(footprints allowed)
			)
			(placement
				(enabled no)
				(sheetname "")
			)
			(fill
				(thermal_gap 0.5)
				(thermal_bridge_width 0.5)
				(island_removal_mode 0)
			)
			(polygon
				(pts
					(xy 373.1514 -91.821) (xy 373.1514 -91.313) (xy 372.7704 -91.313) (xy 372.7704 -91.821)
				)
			)
		)
	)
	(footprint ""
		(layer "B.Cu")
		(at 388.1374 -113.4999)
		(property "Reference" "C3M42"
			(at 0 0 0)
			(layer "B.SilkS")
			(hide yes)
			(effects
				(font
					(size 1.27 1.27)
				)
				(justify mirror)
			)
		)
		(property "Value" ""
			(at 0 0 0)
			(layer "B.Fab")
			(effects
				(font
					(size 1.27 1.27)
				)
				(justify mirror)
			)
		)
		(duplicate_pad_numbers_are_jumpers no)
		(fp_poly
			(pts
				(xy -0.3048 -0.1016) (xy -0.3048 0.9906) (xy 0.3048 0.9906) (xy 0.3048 -0.1016)
			)
			(stroke
				(width 0)
				(type default)
			)
			(fill no)
			(layer "B.CrtYd")
		)
		(fp_line
			(start -0.3048 -0.1016)
			(end 0.3048 -0.1016)
			(stroke
				(width 0.1)
				(type default)
			)
			(layer "B.Fab")
		)
		(fp_line
			(start -0.3048 0.9906)
			(end -0.3048 -0.1016)
			(stroke
				(width 0.1)
				(type default)
			)
			(layer "B.Fab")
		)
		(fp_line
			(start 0.3048 -0.1016)
			(end 0.3048 0.9906)
			(stroke
				(width 0.1)
				(type default)
			)
			(layer "B.Fab")
		)
		(fp_line
			(start 0.3048 0.9906)
			(end -0.3048 0.9906)
			(stroke
				(width 0.1)
				(type default)
			)
			(layer "B.Fab")
		)
		(pad "1" smd rect
			(at 0 0 180)
			(size 0.508 0.508)
			(layers "B.Cu" "B.Mask" "B.Paste")
			(net "P1V05_PCH_STBY")
		)
		(pad "2" smd rect
			(at 0 0.889 180)
			(size 0.508 0.508)
			(layers "B.Cu" "B.Mask" "B.Paste")
			(net "GND")
		)
		(zone
			(layer "B.Cu")
			(hatch none 0.5)
			(connect_pads
				(clearance 0)
			)
			(min_thickness 0.25)
			(keepout
				(tracks allowed)
				(vias not_allowed)
				(pads allowed)
				(copperpour not_allowed)
				(footprints allowed)
			)
			(placement
				(enabled no)
				(sheetname "")
			)
			(fill
				(thermal_gap 0.5)
				(thermal_bridge_width 0.5)
				(island_removal_mode 0)
			)
			(polygon
				(pts
					(xy 388.3914 -113.2459) (xy 387.8834 -113.2459) (xy 387.8834 -112.8649) (xy 388.3914 -112.8649)
				)
			)
		)
		(zone
			(layer "B.Cu")
			(hatch none 0.5)
			(connect_pads
				(clearance 0)
			)
			(min_thickness 0.25)
			(keepout
				(tracks not_allowed)
				(vias allowed)
				(pads allowed)
				(copperpour not_allowed)
				(footprints allowed)
			)
			(placement
				(enabled no)
				(sheetname "")
			)
			(fill
				(thermal_gap 0.5)
				(thermal_bridge_width 0.5)
				(island_removal_mode 0)
			)
			(polygon
				(pts
					(xy 388.3914 -112.8649) (xy 387.8834 -112.8649) (xy 387.8834 -113.2459) (xy 388.3914 -113.2459)
				)
			)
		)
	)
	(footprint ""
		(layer "B.Cu")
		(at 176.149 -77.597 -90)
		(property "Reference" "R6P15"
			(at 0 0 90)
			(layer "B.SilkS")
			(hide yes)
			(effects
				(font
					(size 1.27 1.27)
				)
				(justify mirror)
			)
		)
		(property "Value" ""
			(at 0 0 90)
			(layer "B.Fab")
			(effects
				(font
					(size 1.27 1.27)
				)
				(justify mirror)
			)
		)
		(duplicate_pad_numbers_are_jumpers no)
		(fp_poly
			(pts
				(xy 0.2794 -0.1016) (xy -0.2794 -0.1016) (xy -0.2794 0.9906) (xy 0.2794 0.9906)
			)
			(stroke
				(width 0)
				(type default)
			)
			(fill no)
			(layer "B.CrtYd")
		)
		(fp_line
			(start -0.2794 0.9906)
			(end -0.2794 -0.1016)
			(stroke
				(width 0.1)
				(type default)
			)
			(layer "B.Fab")
		)
		(fp_line
			(start 0.2794 0.9906)
			(end -0.2794 0.9906)
			(stroke
				(width 0.1)
				(type default)
			)
			(layer "B.Fab")
		)
		(fp_line
			(start -0.2794 -0.1016)
			(end 0.2794 -0.1016)
			(stroke
				(width 0.1)
				(type default)
			)
			(layer "B.Fab")
		)
		(fp_line
			(start 0.2794 -0.1016)
			(end 0.2794 0.9906)
			(stroke
				(width 0.1)
				(type default)
			)
			(layer "B.Fab")
		)
		(pad "1" smd rect
			(at 0 0 90)
			(size 0.508 0.508)
			(layers "B.Cu" "B.Mask" "B.Paste")
			(net "CLK_100M_CPU0_BCLK0_DN")
		)
		(pad "2" smd rect
			(at 0 0.889 90)
			(size 0.508 0.508)
			(layers "B.Cu" "B.Mask" "B.Paste")
			(net "GND")
		)
		(zone
			(layer "B.Cu")
			(hatch none 0.5)
			(connect_pads
				(clearance 0)
			)
			(min_thickness 0.25)
			(keepout
				(tracks not_allowed)
				(vias allowed)
				(pads allowed)
				(copperpour not_allowed)
				(footprints allowed)
			)
			(placement
				(enabled no)
				(sheetname "")
			)
			(fill
				(thermal_gap 0.5)
				(thermal_bridge_width 0.5)
				(island_removal_mode 0)
			)
			(polygon
				(pts
					(xy 175.514 -77.343) (xy 175.514 -77.851) (xy 175.895 -77.851) (xy 175.895 -77.343)
				)
			)
		)
		(zone
			(layer "B.Cu")
			(hatch none 0.5)
			(connect_pads
				(clearance 0)
			)
			(min_thickness 0.25)
			(keepout
				(tracks allowed)
				(vias not_allowed)
				(pads allowed)
				(copperpour not_allowed)
				(footprints allowed)
			)
			(placement
				(enabled no)
				(sheetname "")
			)
			(fill
				(thermal_gap 0.5)
				(thermal_bridge_width 0.5)
				(island_removal_mode 0)
			)
			(polygon
				(pts
					(xy 175.895 -77.343) (xy 175.895 -77.851) (xy 175.514 -77.851) (xy 175.514 -77.343)
				)
			)
		)
	)
)
